(kicad_pcb
	(version 20241229)
	(generator "pcbnew")
	(generator_version "9.0")
	(general
		(thickness 1.599998)
		(legacy_teardrops no)
	)
	(paper "A4")
	(title_block
		(title "Artix - Datacenter Secure Control Module (DC-SCM)")
		(date "2024-11-06")
		(rev "1.1.3")
		(comment 9 "footprints 150-153 of 544")
	)
	(layers
		(0 "F.Cu" signal)
		(4 "In1.Cu" signal)
		(6 "In2.Cu" signal)
		(8 "In3.Cu" signal)
		(10 "In4.Cu" signal)
		(12 "In5.Cu" signal)
		(14 "In6.Cu" signal)
		(2 "B.Cu" signal)
		(9 "F.Adhes" user "F.Adhesive")
		(11 "B.Adhes" user "B.Adhesive")
		(13 "F.Paste" user)
		(15 "B.Paste" user)
		(5 "F.SilkS" user "F.Silkscreen")
		(7 "B.SilkS" user "B.Silkscreen")
		(1 "F.Mask" user)
		(3 "B.Mask" user)
		(17 "Dwgs.User" user "User.Drawings")
		(19 "Cmts.User" user "User.Comments")
		(21 "Eco1.User" user "User.Eco1")
		(23 "Eco2.User" user "User.Eco2")
		(25 "Edge.Cuts" user)
		(27 "Margin" user)
		(31 "F.CrtYd" user "F.Courtyard")
		(29 "B.CrtYd" user "B.Courtyard")
		(35 "F.Fab" user)
		(33 "B.Fab" user)
	)
	(footprint "antmicro-footprints:C_1210_3225Metric"
		(layer "F.Cu")
		(at 76.399 84.5)
		(descr "Capacitor SMD 1210")
		(tags "capacitor SMD 1210")
		(property "Reference" "C151"
			(at -2.299 1.4 90)
			(layer "F.SilkS")
			(effects
				(font
					(size 0.7 0.7)
					(thickness 0.15)
				)
				(justify left bottom)
			)
		)
		(property "Value" "C_100u_1210"
			(at 0 2.749 0)
			(layer "F.Fab")
			(effects
				(font
					(size 0.7 0.7)
					(thickness 0.15)
				)
				(justify left bottom)
			)
		)
		(property "Datasheet" "https://product.samsungsem.com/mlcc/CL32A107MQVNNN.do"
			(at 0 0 0)
			(layer "F.Fab")
			(hide yes)
			(effects
				(font
					(size 1.27 1.27)
					(thickness 0.15)
				)
			)
		)
		(property "Description" "SMD Multilayer Ceramic Capacitor, 100 µF, 6.3 V, 1210 [3225 Metric], ± 20%, X5R, CL"
			(at 0 0 0)
			(layer "F.Fab")
			(hide yes)
			(effects
				(font
					(size 1.27 1.27)
					(thickness 0.15)
				)
			)
		)
		(property "Author" "Antmicro"
			(at 0 0 0)
			(layer "F.Fab")
			(hide yes)
			(effects
				(font
					(size 1 1)
					(thickness 0.15)
				)
			)
		)
		(property "Dielectric" ""
			(at 0 0 0)
			(layer "F.Fab")
			(hide yes)
			(effects
				(font
					(size 1 1)
					(thickness 0.15)
				)
			)
		)
		(property "License" "Apache-2.0"
			(at 0 0 0)
			(layer "F.Fab")
			(hide yes)
			(effects
				(font
					(size 1 1)
					(thickness 0.15)
				)
			)
		)
		(property "MPN" "CL32A107MQVNNNE"
			(at 0 0 0)
			(layer "F.Fab")
			(hide yes)
			(effects
				(font
					(size 1 1)
					(thickness 0.15)
				)
			)
		)
		(property "Manufacturer" "Samsung Electro-Mechanics"
			(at 0 0 0)
			(layer "F.Fab")
			(hide yes)
			(effects
				(font
					(size 1 1)
					(thickness 0.15)
				)
			)
		)
		(property "Public" "False"
			(at 0 0 0)
			(layer "F.Fab")
			(hide yes)
			(effects
				(font
					(size 1 1)
					(thickness 0.15)
				)
			)
		)
		(property "Val" "100u"
			(at 0 0 0)
			(layer "F.Fab")
			(hide yes)
			(effects
				(font
					(size 1 1)
					(thickness 0.15)
				)
			)
		)
		(property "Voltage" ""
			(at 0 0 0)
			(layer "F.Fab")
			(hide yes)
			(effects
				(font
					(size 1 1)
					(thickness 0.15)
				)
			)
		)
		(property "DNP" ""
			(at 0 0 0)
			(unlocked yes)
			(layer "F.Fab")
			(hide yes)
			(effects
				(font
					(size 1 1)
					(thickness 0.15)
				)
			)
		)
		(sheetname "/FPGA power supply/")
		(sheetfile "fpga-power-supply.kicad_sch")
		(attr smd)
		(fp_line
			(start -0.3 -1.39)
			(end 0.3 -1.39)
			(stroke
				(width 0.15)
				(type solid)
			)
			(layer "F.SilkS")
		)
		(fp_line
			(start -0.3 1.39)
			(end 0.3 1.39)
			(stroke
				(width 0.15)
				(type solid)
			)
			(layer "F.SilkS")
		)
		(fp_rect
			(start -2.1 -1.75)
			(end 2.1 1.75)
			(stroke
				(width 0.05)
				(type solid)
			)
			(fill no)
			(layer "F.CrtYd")
		)
		(fp_rect
			(start -1.6 -1.25)
			(end 1.6 1.25)
			(stroke
				(width 0.15)
				(type solid)
			)
			(fill no)
			(layer "F.Fab")
		)
		(pad "1" smd rect
			(at -1.145 0)
			(size 1.52 3.05)
			(layers "F.Cu" "F.Mask" "F.Paste")
			(net 1 "GND")
			(pintype "passive")
		)
		(pad "2" smd rect
			(at 1.145 0)
			(size 1.52 3.05)
			(layers "F.Cu" "F.Mask" "F.Paste")
			(net 6 "VCC1V0")
			(pintype "passive")
		)
	)
	(footprint "antmicro-footprints:LED_0603_1608Metric_G"
		(layer "F.Cu")
		(at 75.719 91.899 180)
		(descr "LED SMD 0603 Green")
		(tags "LED SMD 0603 Green")
		(property "Reference" "D4"
			(at -2.781 -0.401 0)
			(layer "F.SilkS")
			(effects
				(font
					(size 0.7 0.7)
					(thickness 0.15)
				)
				(justify right bottom)
			)
		)
		(property "Value" "LED_G_0603_LG_L29K-G2J1-24-Z"
			(at 0 1.6 0)
			(layer "F.Fab")
			(effects
				(font
					(size 0.7 0.7)
					(thickness 0.15)
				)
				(justify right bottom)
			)
		)
		(property "Datasheet" "https://look.ams-osram.com/m/19ee86b3ae0ee95b/original/LG-L29K.pdf"
			(at 0 0 180)
			(layer "F.Fab")
			(hide yes)
			(effects
				(font
					(size 1.27 1.27)
					(thickness 0.15)
				)
			)
		)
		(property "Description" "LED, Green, SMD, 0603, 20 mA, 1.7 V, 570 nm"
			(at 0 0 180)
			(layer "F.Fab")
			(hide yes)
			(effects
				(font
					(size 1.27 1.27)
					(thickness 0.15)
				)
			)
		)
		(property "Author" "Antmicro"
			(at 151.438 183.798 0)
			(layer "F.Fab")
			(hide yes)
			(effects
				(font
					(size 1 1)
					(thickness 0.15)
				)
			)
		)
		(property "Color" "Green"
			(at 151.438 183.798 0)
			(layer "F.Fab")
			(hide yes)
			(effects
				(font
					(size 1 1)
					(thickness 0.15)
				)
			)
		)
		(property "License" "Apache-2.0"
			(at 151.438 183.798 0)
			(layer "F.Fab")
			(hide yes)
			(effects
				(font
					(size 1 1)
					(thickness 0.15)
				)
			)
		)
		(property "MPN" "LG L29K-G2J1-24-Z"
			(at 151.438 183.798 0)
			(layer "F.Fab")
			(hide yes)
			(effects
				(font
					(size 1 1)
					(thickness 0.15)
				)
			)
		)
		(property "Manufacturer" "OSRAM"
			(at 151.438 183.798 0)
			(layer "F.Fab")
			(hide yes)
			(effects
				(font
					(size 1 1)
					(thickness 0.15)
				)
			)
		)
		(sheetname "/Power supply/")
		(sheetfile "power-supply.kicad_sch")
		(attr smd)
		(fp_line
			(start 0.22 0.35)
			(end -0.22 0.35)
			(stroke
				(width 0.15)
				(type solid)
			)
			(layer "F.SilkS")
		)
		(fp_line
			(start 0.22 -0.35)
			(end -0.22 -0.35)
			(stroke
				(width 0.15)
				(type solid)
			)
			(layer "F.SilkS")
		)
		(fp_line
			(start 0.105328 0.201008)
			(end 0.105328 -0.198992)
			(stroke
				(width 0.1)
				(type solid)
			)
			(layer "F.SilkS")
		)
		(fp_line
			(start 0.105328 0.201008)
			(end -0.094672 0.001008)
			(stroke
				(width 0.1)
				(type solid)
			)
			(layer "F.SilkS")
		)
		(fp_line
			(start 0.105328 0.001008)
			(end 0.24 0.001)
			(stroke
				(width 0.1)
				(type solid)
			)
			(layer "F.SilkS")
		)
		(fp_line
			(start -0.094672 0.201008)
			(end -0.094672 -0.198992)
			(stroke
				(width 0.1)
				(type solid)
			)
			(layer "F.SilkS")
		)
		(fp_line
			(start -0.094672 0.001008)
			(end 0.105328 -0.198992)
			(stroke
				(width 0.1)
				(type solid)
			)
			(layer "F.SilkS")
		)
		(fp_line
			(start -0.094672 0.001008)
			(end -0.24 0.001008)
			(stroke
				(width 0.1)
				(type solid)
			)
			(layer "F.SilkS")
		)
		(fp_line
			(start -1.18 -0.319)
			(end -1.18 0.321)
			(stroke
				(width 0.15)
				(type solid)
			)
			(layer "F.SilkS")
		)
		(fp_rect
			(start 1.25 0.65)
			(end -1.25 -0.65)
			(stroke
				(width 0.05)
				(type solid)
			)
			(fill no)
			(layer "F.CrtYd")
		)
		(fp_line
			(start 0.599 0)
			(end 0.201 0)
			(stroke
				(width 0.15)
				(type solid)
			)
			(layer "F.Fab")
		)
		(fp_line
			(start 0.201 0.2)
			(end 0.201 0)
			(stroke
				(width 0.15)
				(type solid)
			)
			(layer "F.Fab")
		)
		(fp_line
			(start 0.201 0)
			(end 0.201 -0.202)
			(stroke
				(width 0.15)
				(type solid)
			)
			(layer "F.Fab")
		)
		(fp_line
			(start 0.201 -0.202)
			(end -0.101 0)
			(stroke
				(width 0.15)
				(type solid)
			)
			(layer "F.Fab")
		)
		(fp_line
			(start -0.101 0)
			(end 0.201 0.2)
			(stroke
				(width 0.15)
				(type solid)
			)
			(layer "F.Fab")
		)
		(fp_line
			(start -0.199 0.2)
			(end -0.199 0.1)
			(stroke
				(width 0.15)
				(type solid)
			)
			(layer "F.Fab")
		)
		(fp_line
			(start -0.199 0)
			(end -0.597 0)
			(stroke
				(width 0.15)
				(type solid)
			)
			(layer "F.Fab")
		)
		(fp_line
			(start -0.199 -0.202)
			(end -0.199 0.1)
			(stroke
				(width 0.15)
				(type solid)
			)
			(layer "F.Fab")
		)
		(fp_rect
			(start 0.848 0.4)
			(end -0.85 -0.402)
			(stroke
				(width 0.15)
				(type solid)
			)
			(fill no)
			(layer "F.Fab")
		)
		(pad "1" smd roundrect
			(at -0.7 0)
			(size 0.8 1)
			(layers "F.Cu" "F.Mask" "F.Paste")
			(roundrect_rratio 0.2)
			(net 207 "Net-(D4-C)")
			(pinfunction "C")
			(pintype "passive")
		)
		(pad "2" smd roundrect
			(at 0.7 0)
			(size 0.8 1)
			(layers "F.Cu" "F.Mask" "F.Paste")
			(roundrect_rratio 0.2)
			(net 208 "Net-(D4-A)")
			(pinfunction "A")
			(pintype "passive")
		)
	)
	(footprint "antmicro-footprints:LED_0603_1608Metric_G"
		(layer "F.Cu")
		(at 75.719 89.867 180)
		(descr "LED SMD 0603 Green")
		(tags "LED SMD 0603 Green")
		(property "Reference" "D5"
			(at -2.781 -0.433 0)
			(layer "F.SilkS")
			(effects
				(font
					(size 0.7 0.7)
					(thickness 0.15)
				)
				(justify right bottom)
			)
		)
		(property "Value" "LED_G_0603_LG_L29K-G2J1-24-Z"
			(at 0 1.6 0)
			(layer "F.Fab")
			(effects
				(font
					(size 0.7 0.7)
					(thickness 0.15)
				)
				(justify right bottom)
			)
		)
		(property "Datasheet" "https://look.ams-osram.com/m/19ee86b3ae0ee95b/original/LG-L29K.pdf"
			(at 0 0 180)
			(layer "F.Fab")
			(hide yes)
			(effects
				(font
					(size 1.27 1.27)
					(thickness 0.15)
				)
			)
		)
		(property "Description" "LED, Green, SMD, 0603, 20 mA, 1.7 V, 570 nm"
			(at 0 0 180)
			(layer "F.Fab")
			(hide yes)
			(effects
				(font
					(size 1.27 1.27)
					(thickness 0.15)
				)
			)
		)
		(property "Author" "Antmicro"
			(at 151.438 179.734 0)
			(layer "F.Fab")
			(hide yes)
			(effects
				(font
					(size 1 1)
					(thickness 0.15)
				)
			)
		)
		(property "Color" "Green"
			(at 151.438 179.734 0)
			(layer "F.Fab")
			(hide yes)
			(effects
				(font
					(size 1 1)
					(thickness 0.15)
				)
			)
		)
		(property "License" "Apache-2.0"
			(at 151.438 179.734 0)
			(layer "F.Fab")
			(hide yes)
			(effects
				(font
					(size 1 1)
					(thickness 0.15)
				)
			)
		)
		(property "MPN" "LG L29K-G2J1-24-Z"
			(at 151.438 179.734 0)
			(layer "F.Fab")
			(hide yes)
			(effects
				(font
					(size 1 1)
					(thickness 0.15)
				)
			)
		)
		(property "Manufacturer" "OSRAM"
			(at 151.438 179.734 0)
			(layer "F.Fab")
			(hide yes)
			(effects
				(font
					(size 1 1)
					(thickness 0.15)
				)
			)
		)
		(sheetname "/Power supply/")
		(sheetfile "power-supply.kicad_sch")
		(attr smd)
		(fp_line
			(start 0.22 0.35)
			(end -0.22 0.35)
			(stroke
				(width 0.15)
				(type solid)
			)
			(layer "F.SilkS")
		)
		(fp_line
			(start 0.22 -0.35)
			(end -0.22 -0.35)
			(stroke
				(width 0.15)
				(type solid)
			)
			(layer "F.SilkS")
		)
		(fp_line
			(start 0.105328 0.201008)
			(end 0.105328 -0.198992)
			(stroke
				(width 0.1)
				(type solid)
			)
			(layer "F.SilkS")
		)
		(fp_line
			(start 0.105328 0.201008)
			(end -0.094672 0.001008)
			(stroke
				(width 0.1)
				(type solid)
			)
			(layer "F.SilkS")
		)
		(fp_line
			(start 0.105328 0.001008)
			(end 0.24 0.001)
			(stroke
				(width 0.1)
				(type solid)
			)
			(layer "F.SilkS")
		)
		(fp_line
			(start -0.094672 0.201008)
			(end -0.094672 -0.198992)
			(stroke
				(width 0.1)
				(type solid)
			)
			(layer "F.SilkS")
		)
		(fp_line
			(start -0.094672 0.001008)
			(end 0.105328 -0.198992)
			(stroke
				(width 0.1)
				(type solid)
			)
			(layer "F.SilkS")
		)
		(fp_line
			(start -0.094672 0.001008)
			(end -0.24 0.001008)
			(stroke
				(width 0.1)
				(type solid)
			)
			(layer "F.SilkS")
		)
		(fp_line
			(start -1.18 -0.319)
			(end -1.18 0.321)
			(stroke
				(width 0.15)
				(type solid)
			)
			(layer "F.SilkS")
		)
		(fp_rect
			(start 1.25 0.65)
			(end -1.25 -0.65)
			(stroke
				(width 0.05)
				(type solid)
			)
			(fill no)
			(layer "F.CrtYd")
		)
		(fp_line
			(start 0.599 0)
			(end 0.201 0)
			(stroke
				(width 0.15)
				(type solid)
			)
			(layer "F.Fab")
		)
		(fp_line
			(start 0.201 0.2)
			(end 0.201 0)
			(stroke
				(width 0.15)
				(type solid)
			)
			(layer "F.Fab")
		)
		(fp_line
			(start 0.201 0)
			(end 0.201 -0.202)
			(stroke
				(width 0.15)
				(type solid)
			)
			(layer "F.Fab")
		)
		(fp_line
			(start 0.201 -0.202)
			(end -0.101 0)
			(stroke
				(width 0.15)
				(type solid)
			)
			(layer "F.Fab")
		)
		(fp_line
			(start -0.101 0)
			(end 0.201 0.2)
			(stroke
				(width 0.15)
				(type solid)
			)
			(layer "F.Fab")
		)
		(fp_line
			(start -0.199 0.2)
			(end -0.199 0.1)
			(stroke
				(width 0.15)
				(type solid)
			)
			(layer "F.Fab")
		)
		(fp_line
			(start -0.199 0)
			(end -0.597 0)
			(stroke
				(width 0.15)
				(type solid)
			)
			(layer "F.Fab")
		)
		(fp_line
			(start -0.199 -0.202)
			(end -0.199 0.1)
			(stroke
				(width 0.15)
				(type solid)
			)
			(layer "F.Fab")
		)
		(fp_rect
			(start 0.848 0.4)
			(end -0.85 -0.402)
			(stroke
				(width 0.15)
				(type solid)
			)
			(fill no)
			(layer "F.Fab")
		)
		(pad "1" smd roundrect
			(at -0.7 0)
			(size 0.8 1)
			(layers "F.Cu" "F.Mask" "F.Paste")
			(roundrect_rratio 0.2)
			(net 214 "Net-(D5-C)")
			(pinfunction "C")
			(pintype "passive")
		)
		(pad "2" smd roundrect
			(at 0.7 0)
			(size 0.8 1)
			(layers "F.Cu" "F.Mask" "F.Paste")
			(roundrect_rratio 0.2)
			(net 215 "Net-(D5-A)")
			(pinfunction "A")
			(pintype "passive")
		)
	)
	(footprint "antmicro-footprints:LED_0603_1608Metric_G"
		(layer "F.Cu")
		(at 75.719 95.963 180)
		(descr "LED SMD 0603 Green")
		(tags "LED SMD 0603 Green")
		(property "Reference" "D6"
			(at -2.781 -0.437 0)
			(layer "F.SilkS")
			(effects
				(font
					(size 0.7 0.7)
					(thickness 0.15)
				)
				(justify right bottom)
			)
		)
		(property "Value" "LED_G_0603_LG_L29K-G2J1-24-Z"
			(at 0 1.6 0)
			(layer "F.Fab")
			(effects
				(font
					(size 0.7 0.7)
					(thickness 0.15)
				)
				(justify right bottom)
			)
		)
		(property "Datasheet" "https://look.ams-osram.com/m/19ee86b3ae0ee95b/original/LG-L29K.pdf"
			(at 0 0 180)
			(layer "F.Fab")
			(hide yes)
			(effects
				(font
					(size 1.27 1.27)
					(thickness 0.15)
				)
			)
		)
		(property "Description" "LED, Green, SMD, 0603, 20 mA, 1.7 V, 570 nm"
			(at 0 0 180)
			(layer "F.Fab")
			(hide yes)
			(effects
				(font
					(size 1.27 1.27)
					(thickness 0.15)
				)
			)
		)
		(property "Author" "Antmicro"
			(at 151.438 191.926 0)
			(layer "F.Fab")
			(hide yes)
			(effects
				(font
					(size 1 1)
					(thickness 0.15)
				)
			)
		)
		(property "Color" "Green"
			(at 151.438 191.926 0)
			(layer "F.Fab")
			(hide yes)
			(effects
				(font
					(size 1 1)
					(thickness 0.15)
				)
			)
		)
		(property "License" "Apache-2.0"
			(at 151.438 191.926 0)
			(layer "F.Fab")
			(hide yes)
			(effects
				(font
					(size 1 1)
					(thickness 0.15)
				)
			)
		)
		(property "MPN" "LG L29K-G2J1-24-Z"
			(at 151.438 191.926 0)
			(layer "F.Fab")
			(hide yes)
			(effects
				(font
					(size 1 1)
					(thickness 0.15)
				)
			)
		)
		(property "Manufacturer" "OSRAM"
			(at 151.438 191.926 0)
			(layer "F.Fab")
			(hide yes)
			(effects
				(font
					(size 1 1)
					(thickness 0.15)
				)
			)
		)
		(sheetname "/Power supply/")
		(sheetfile "power-supply.kicad_sch")
		(attr smd)
		(fp_line
			(start 0.22 0.35)
			(end -0.22 0.35)
			(stroke
				(width 0.15)
				(type solid)
			)
			(layer "F.SilkS")
		)
		(fp_line
			(start 0.22 -0.35)
			(end -0.22 -0.35)
			(stroke
				(width 0.15)
				(type solid)
			)
			(layer "F.SilkS")
		)
		(fp_line
			(start 0.105328 0.201008)
			(end 0.105328 -0.198992)
			(stroke
				(width 0.1)
				(type solid)
			)
			(layer "F.SilkS")
		)
		(fp_line
			(start 0.105328 0.201008)
			(end -0.094672 0.001008)
			(stroke
				(width 0.1)
				(type solid)
			)
			(layer "F.SilkS")
		)
		(fp_line
			(start 0.105328 0.001008)
			(end 0.24 0.001)
			(stroke
				(width 0.1)
				(type solid)
			)
			(layer "F.SilkS")
		)
		(fp_line
			(start -0.094672 0.201008)
			(end -0.094672 -0.198992)
			(stroke
				(width 0.1)
				(type solid)
			)
			(layer "F.SilkS")
		)
		(fp_line
			(start -0.094672 0.001008)
			(end 0.105328 -0.198992)
			(stroke
				(width 0.1)
				(type solid)
			)
			(layer "F.SilkS")
		)
		(fp_line
			(start -0.094672 0.001008)
			(end -0.24 0.001008)
			(stroke
				(width 0.1)
				(type solid)
			)
			(layer "F.SilkS")
		)
		(fp_line
			(start -1.18 -0.319)
			(end -1.18 0.321)
			(stroke
				(width 0.15)
				(type solid)
			)
			(layer "F.SilkS")
		)
		(fp_rect
			(start 1.25 0.65)
			(end -1.25 -0.65)
			(stroke
				(width 0.05)
				(type solid)
			)
			(fill no)
			(layer "F.CrtYd")
		)
		(fp_line
			(start 0.599 0)
			(end 0.201 0)
			(stroke
				(width 0.15)
				(type solid)
			)
			(layer "F.Fab")
		)
		(fp_line
			(start 0.201 0.2)
			(end 0.201 0)
			(stroke
				(width 0.15)
				(type solid)
			)
			(layer "F.Fab")
		)
		(fp_line
			(start 0.201 0)
			(end 0.201 -0.202)
			(stroke
				(width 0.15)
				(type solid)
			)
			(layer "F.Fab")
		)
		(fp_line
			(start 0.201 -0.202)
			(end -0.101 0)
			(stroke
				(width 0.15)
				(type solid)
			)
			(layer "F.Fab")
		)
		(fp_line
			(start -0.101 0)
			(end 0.201 0.2)
			(stroke
				(width 0.15)
				(type solid)
			)
			(layer "F.Fab")
		)
		(fp_line
			(start -0.199 0.2)
			(end -0.199 0.1)
			(stroke
				(width 0.15)
				(type solid)
			)
			(layer "F.Fab")
		)
		(fp_line
			(start -0.199 0)
			(end -0.597 0)
			(stroke
				(width 0.15)
				(type solid)
			)
			(layer "F.Fab")
		)
		(fp_line
			(start -0.199 -0.202)
			(end -0.199 0.1)
			(stroke
				(width 0.15)
				(type solid)
			)
			(layer "F.Fab")
		)
		(fp_rect
			(start 0.848 0.4)
			(end -0.85 -0.402)
			(stroke
				(width 0.15)
				(type solid)
			)
			(fill no)
			(layer "F.Fab")
		)
		(pad "1" smd roundrect
			(at -0.7 0)
			(size 0.8 1)
			(layers "F.Cu" "F.Mask" "F.Paste")
			(roundrect_rratio 0.2)
			(net 216 "Net-(D6-C)")
			(pinfunction "C")
			(pintype "passive")
		)
		(pad "2" smd roundrect
			(at 0.7 0)
			(size 0.8 1)
			(layers "F.Cu" "F.Mask" "F.Paste")
			(roundrect_rratio 0.2)
			(net 217 "Net-(D6-A)")
			(pinfunction "A")
			(pintype "passive")
		)
	)
)
